# T6G (Grand Teton) — schematic netlist excerpt (pin names and nets, part order shuffled) for the footprints in the layout excerpt that follows; sources: Cadence DE-HDL packaged netlist, KiCad conversion of 04192023_DAF0TMB3IC0_F0TG_MB_C_brd_V02_OCP.brd

PC8010  Q_CAP  22UF 16V 20% X6S  pkg C0805  page 198 : A = SW_P12V_AUX_PVDDCR_SOC_P0_FLT ; B = GND

X25  TP_TDR_4P_FTS  TP_TDR_4P_DIP EMPTY  pkg TH  page 260
  S1  = TDR_DIFF_80_IN5_DP
  P1  = T1_GND
  P2  = T1_GND
  S2  = TDR_DIFF_80_IN5_DN

C6728  Q_CAP_DIFFBUS  DIFF BUS_0.22UF 6.3V 20% X6S  pkg C0201  page 352 : \1\ = P5E_CPU1_P3_TX_BUF_C_DN<1> ; \2\ = P5E_CPU1_P3_TX_BUF_DN<1>

(kicad_pcb
	(version 20260206)
	(generator "pcbnew")
	(generator_version "10.0")
	(general
		(thickness 1.6)
		(legacy_teardrops no)
	)
	(paper "A4")
	(title_block
		(title "04192023_DAF0TMB3IC0_F0TG_MB_C_brd_V02_OCP.brd")
		(comment 1 "Grand Teton / footprints 8281-8283 of 8354")
	)
	(layers
		(0 "F.Cu" signal "TOP")
		(4 "In1.Cu" signal "GND")
		(6 "In2.Cu" signal "IN1")
		(8 "In3.Cu" signal "GND1")
		(10 "In4.Cu" signal "IN2")
		(12 "In5.Cu" signal "GND2")
		(14 "In6.Cu" signal "IN3")
		(16 "In7.Cu" signal "GND3")
		(18 "In8.Cu" signal "VCC")
		(20 "In9.Cu" signal "VCC1")
		(22 "In10.Cu" signal "GND4")
		(24 "In11.Cu" signal "IN4")
		(26 "In12.Cu" signal "GND5")
		(28 "In13.Cu" signal "IN5")
		(30 "In14.Cu" signal "GND6")
		(32 "In15.Cu" signal "IN6")
		(34 "In16.Cu" signal "GND7")
		(2 "B.Cu" signal "BOTTOM")
		(9 "F.Adhes" user "F.Adhesive")
		(11 "B.Adhes" user "B.Adhesive")
		(13 "F.Paste" user "Package Geometry/Pastemask Top")
		(15 "B.Paste" user "Package Geometry/Pastemask Bottom")
		(5 "F.SilkS" user "Ref Des/Silkscreen Top")
		(7 "B.SilkS" user "Ref Des/Silkscreen Bottom")
		(1 "F.Mask" user "Board Geometry/Soldermask Top")
		(3 "B.Mask" user "Board Geometry/Soldermask Bottom")
		(17 "Dwgs.User" user "User.Drawings")
		(19 "Cmts.User" user "User.Comments")
		(21 "Eco1.User" user "User.Eco1")
		(23 "Eco2.User" user "User.Eco2")
		(25 "Edge.Cuts" user "Board Geometry/Outline")
		(27 "Margin" user)
		(31 "F.CrtYd" user "Package Geometry/Place Bound Top")
		(29 "B.CrtYd" user "Package Geometry/Place Bound Bottom")
		(35 "F.Fab" user "Ref Des/Assembly Top")
		(33 "B.Fab" user "Ref Des/Assembly Bottom")
	)
	(footprint ""
		(layer "B.Cu")
		(at 509.384808 -147.926806 90)
		(property "Reference" "X25"
			(at 0.885444 3.130042 270)
			(unlocked yes)
			(layer "B.SilkS")
			(effects
				(font
					(size 0.7874 0.5842)
					(thickness 0.1524)
				)
				(justify left mirror)
			)
		)
		(property "Value" ""
			(at 0 0 90)
			(layer "B.Fab")
			(effects
				(font
					(size 1.27 1.27)
				)
				(justify mirror)
			)
		)
		(property "Device Type" "TP_TDR_4P_FTS_TH-TP_TDR_4P_DIP,EMPTY,TP15"
			(at -1.30175 1.27 0)
			(unlocked yes)
			(layer "B.Fab")
			(hide yes)
			(effects
				(font
					(size 0.635 0.4064)
					(thickness 0.1524)
				)
				(justify mirror)
			)
		)
		(property "User Part Number" "N_A"
			(at -1.30175 1.27 0)
			(unlocked yes)
			(layer "Cmts.User")
			(hide yes)
			(effects
				(font
					(size 0.635 0.4064)
					(thickness 0.1524)
				)
				(justify mirror)
			)
		)
		(duplicate_pad_numbers_are_jumpers no)
		(fp_line
			(start 0 -1.27)
			(end 0 -0.635)
			(stroke
				(width 0.1524)
				(type default)
			)
			(layer "B.SilkS")
		)
		(fp_line
			(start -2.54 -1.27)
			(end 0 -1.27)
			(stroke
				(width 0.1524)
				(type default)
			)
			(layer "B.SilkS")
		)
		(fp_line
			(start -2.54 -1.1303)
			(end -2.54 -1.27)
			(stroke
				(width 0.1524)
				(type default)
			)
			(layer "B.SilkS")
		)
		(fp_line
			(start 0 0.635)
			(end 0 1.905)
			(stroke
				(width 0.1524)
				(type default)
			)
			(layer "B.SilkS")
		)
		(fp_line
			(start -2.54 1.4097)
			(end -2.54 1.1303)
			(stroke
				(width 0.1524)
				(type default)
			)
			(layer "B.SilkS")
		)
		(fp_line
			(start 0 3.175)
			(end 0 3.81)
			(stroke
				(width 0.1524)
				(type default)
			)
			(layer "B.SilkS")
		)
		(fp_line
			(start 0 3.81)
			(end -2.54 3.81)
			(stroke
				(width 0.1524)
				(type default)
			)
			(layer "B.SilkS")
		)
		(fp_line
			(start -2.54 3.81)
			(end -2.54 3.6703)
			(stroke
				(width 0.1524)
				(type default)
			)
			(layer "B.SilkS")
		)
		(fp_poly
			(pts
				(xy 2.285746 -0.762) (xy 2.285746 0.762) (xy 0.761746 0)
			)
			(stroke
				(width 0)
				(type default)
			)
			(fill yes)
			(layer "B.SilkS")
		)
		(fp_line
			(start 0 -1.27)
			(end 0 3.81)
			(stroke
				(width 0.1)
				(type default)
			)
			(layer "B.Fab")
		)
		(fp_line
			(start -2.54 -1.27)
			(end 0 -1.27)
			(stroke
				(width 0.1)
				(type default)
			)
			(layer "B.Fab")
		)
		(fp_line
			(start 0 3.81)
			(end -2.54 3.81)
			(stroke
				(width 0.1)
				(type default)
			)
			(layer "B.Fab")
		)
		(fp_line
			(start -2.54 3.81)
			(end -2.54 -1.27)
			(stroke
				(width 0.1)
				(type default)
			)
			(layer "B.Fab")
		)
		(fp_poly
			(pts
				(xy 0.761746 0) (xy 2.285746 -0.762) (xy 2.285746 0.762)
			)
			(stroke
				(width 0)
				(type default)
			)
			(fill yes)
			(layer "B.Fab")
		)
		(pad "1" thru_hole circle
			(at 0 0 270)
			(size 1.0033 1.0033)
			(drill 0.249936)
			(layers "*.Cu" "*.Mask")
			(remove_unused_layers no)
			(net "TDR_DIFF_80_IN5_DP")
			(clearance 0.10795)
			(padstack
				(mode front_inner_back)
				(layer "Inner"
					(shape circle)
					(size 0.8001 0.8001)
					(clearance 0.1524)
				)
				(layer "B.Cu"
					(shape circle)
					(size 1.0033 1.0033)
					(thermal_gap 0.10795)
					(clearance 0.10795)
				)
			)
		)
		(pad "2" thru_hole circle
			(at -2.54 0 270)
			(size 1.9939 1.9939)
			(drill 0.249936)
			(layers "*.Cu" "*.Mask")
			(remove_unused_layers no)
			(net "T1_GND")
			(clearance 0.10795)
			(padstack
				(mode front_inner_back)
				(layer "Inner"
					(shape circle)
					(size 0.8001 0.8001)
					(clearance 0.1524)
				)
				(layer "B.Cu"
					(shape circle)
					(size 1.9939 1.9939)
					(thermal_gap 0.10795)
					(clearance 0.10795)
				)
			)
		)
		(pad "3" thru_hole circle
			(at -2.54 2.54 270)
			(size 1.9939 1.9939)
			(drill 0.249936)
			(layers "*.Cu" "*.Mask")
			(remove_unused_layers no)
			(net "T1_GND")
			(clearance 0.10795)
			(padstack
				(mode front_inner_back)
				(layer "Inner"
					(shape circle)
					(size 0.8001 0.8001)
					(clearance 0.1524)
				)
				(layer "B.Cu"
					(shape circle)
					(size 1.9939 1.9939)
					(thermal_gap 0.10795)
					(clearance 0.10795)
				)
			)
		)
		(pad "4" thru_hole circle
			(at 0 2.54 270)
			(size 1.0033 1.0033)
			(drill 0.249936)
			(layers "*.Cu" "*.Mask")
			(remove_unused_layers no)
			(net "TDR_DIFF_80_IN5_DN")
			(clearance 0.10795)
			(padstack
				(mode front_inner_back)
				(layer "Inner"
					(shape circle)
					(size 0.8001 0.8001)
					(clearance 0.1524)
				)
				(layer "B.Cu"
					(shape circle)
					(size 1.0033 1.0033)
					(thermal_gap 0.10795)
					(clearance 0.10795)
				)
			)
		)
	)
	(footprint ""
		(layer "B.Cu")
		(at 407.543254 -162.237928 -90)
		(property "Reference" "PC8010"
			(at 0 0 90)
			(layer "B.SilkS")
			(hide yes)
			(effects
				(font
					(size 1.27 1.27)
				)
				(justify mirror)
			)
		)
		(property "Value" ""
			(at 0 0 90)
			(layer "B.Fab")
			(effects
				(font
					(size 1.27 1.27)
				)
				(justify mirror)
			)
		)
		(duplicate_pad_numbers_are_jumpers no)
		(fp_line
			(start -1.524 0.762)
			(end 1.524 0.762)
			(stroke
				(width 0.1524)
				(type default)
			)
			(layer "B.SilkS")
		)
		(fp_line
			(start 1.524 0.762)
			(end 1.524 -0.762)
			(stroke
				(width 0.1524)
				(type default)
			)
			(layer "B.SilkS")
		)
		(fp_line
			(start -1.524 -0.762)
			(end -1.524 0.762)
			(stroke
				(width 0.1524)
				(type default)
			)
			(layer "B.SilkS")
		)
		(fp_line
			(start 1.524 -0.762)
			(end -1.524 -0.762)
			(stroke
				(width 0.1524)
				(type default)
			)
			(layer "B.SilkS")
		)
		(fp_line
			(start -1.1049 0.724916)
			(end -1.1049 -0.724916)
			(stroke
				(width 0.1)
				(type default)
			)
			(layer "B.Fab")
		)
		(fp_line
			(start 1.1049 0.724916)
			(end -1.1049 0.724916)
			(stroke
				(width 0.1)
				(type default)
			)
			(layer "B.Fab")
		)
		(fp_line
			(start -1.1049 -0.724916)
			(end 1.1049 -0.724916)
			(stroke
				(width 0.1)
				(type default)
			)
			(layer "B.Fab")
		)
		(fp_line
			(start 1.1049 -0.724916)
			(end 1.1049 0.724916)
			(stroke
				(width 0.1)
				(type default)
			)
			(layer "B.Fab")
		)
		(pad "1" smd rect
			(at 0.889 0 270)
			(size 1.016 1.27)
			(layers "B.Cu" "B.Mask" "B.Paste")
			(net "SW_P12V_AUX_PVDDCR_SOC_P0_FLT")
		)
		(pad "2" smd rect
			(at -0.889 0 270)
			(size 1.016 1.27)
			(layers "B.Cu" "B.Mask" "B.Paste")
			(net "GND")
		)
	)
	(footprint ""
		(layer "B.Cu")
		(at 119.463566 -408.517344 90)
		(property "Reference" "C6728"
			(at 0 0 90)
			(layer "B.SilkS")
			(hide yes)
			(effects
				(font
					(size 1.27 1.27)
				)
				(justify mirror)
			)
		)
		(property "Value" ""
			(at 0 0 90)
			(layer "B.Fab")
			(effects
				(font
					(size 1.27 1.27)
				)
				(justify mirror)
			)
		)
		(duplicate_pad_numbers_are_jumpers no)
		(fp_line
			(start 0.299974 -0.150114)
			(end -0.299974 -0.150114)
			(stroke
				(width 0.1)
				(type default)
			)
			(layer "B.Fab")
		)
		(fp_line
			(start -0.299974 -0.150114)
			(end -0.299974 0.150114)
			(stroke
				(width 0.1)
				(type default)
			)
			(layer "B.Fab")
		)
		(fp_line
			(start 0.299974 0.150114)
			(end 0.299974 -0.150114)
			(stroke
				(width 0.1)
				(type default)
			)
			(layer "B.Fab")
		)
		(fp_line
			(start -0.299974 0.150114)
			(end 0.299974 0.150114)
			(stroke
				(width 0.1)
				(type default)
			)
			(layer "B.Fab")
		)
		(pad "1" smd rect
			(at 0.2667 0 270)
			(size 0.3048 0.381)
			(layers "B.Cu" "B.Mask" "B.Paste")
			(net "P5E_CPU1_P3_TX_BUF_C_DN<1>")
		)
		(pad "2" smd rect
			(at -0.2667 0 270)
			(size 0.3048 0.381)
			(layers "B.Cu" "B.Mask" "B.Paste")
			(net "P5E_CPU1_P3_TX_BUF_DN<1>")
		)
	)
)
